G04*
G04 #@! TF.GenerationSoftware,Altium Limited,Altium Designer,23.6.0 (18)*
G04*
G04 Layer_Physical_Order=2*
G04 Layer_Color=36540*
%FSLAX44Y44*%
%MOMM*%
G71*
G04*
G04 #@! TF.SameCoordinates,59133E90-4310-4D8A-9E2C-91A8D2F69FBB*
G04*
G04*
G04 #@! TF.FilePolarity,Positive*
G04*
G01*
G75*
%ADD58C,0.4064*%
%ADD59C,5.5000*%
G36*
X215922Y35578D02*
X214580D01*
X214061Y36461D01*
X213984Y36820D01*
X214458Y37963D01*
Y39277D01*
X213955Y40490D01*
X213026Y41419D01*
X211812Y41922D01*
X210499D01*
X209285Y41419D01*
X208572Y40706D01*
X207990Y40708D01*
X207701Y40767D01*
X207189Y40982D01*
X206799Y41924D01*
X205870Y42853D01*
X204657Y43356D01*
X203343D01*
X202130Y42853D01*
X201201Y41924D01*
X200698Y40710D01*
Y39397D01*
X201201Y38183D01*
X202130Y37254D01*
X203343Y36752D01*
X204657D01*
X205870Y37254D01*
X206584Y37968D01*
X207166Y37965D01*
X207455Y37907D01*
X207966Y37691D01*
X208356Y36749D01*
X209285Y35821D01*
X209623Y35680D01*
X209764Y35069D01*
X209691Y34278D01*
X208588Y33541D01*
X207209Y32162D01*
X207209Y32162D01*
X206325Y30839D01*
X205578Y29036D01*
X205571Y29000D01*
X177513D01*
X176309Y29400D01*
X176193Y30570D01*
X176019Y31144D01*
X175902Y31731D01*
X175007Y33894D01*
X174123Y35217D01*
X172467Y36872D01*
X171144Y37757D01*
X171144Y37757D01*
X168981Y38652D01*
X168981Y38653D01*
X167421Y38963D01*
X165079D01*
X163519Y38653D01*
X163519Y38652D01*
X161356Y37757D01*
X160033Y36872D01*
X158377Y35217D01*
X157493Y33894D01*
X157493Y33894D01*
X156597Y31731D01*
X156481Y31144D01*
X156307Y30570D01*
X156191Y29400D01*
X154987Y29000D01*
X37120D01*
X36272Y30270D01*
X36302Y30343D01*
Y31657D01*
X35799Y32870D01*
X34870Y33799D01*
X34838Y33813D01*
Y35187D01*
X34870Y35201D01*
X35799Y36130D01*
X36302Y37343D01*
Y38657D01*
X35799Y39870D01*
X34870Y40799D01*
X34578Y40921D01*
Y42295D01*
X34750Y42367D01*
X35679Y43295D01*
X36182Y44509D01*
Y45823D01*
X35679Y47036D01*
X35135Y47581D01*
X34943Y48496D01*
X35185Y49160D01*
X35799Y49775D01*
X36302Y50988D01*
Y52302D01*
X35799Y53516D01*
X34870Y54444D01*
X33657Y54947D01*
X32343D01*
X31130Y54444D01*
X30201Y53516D01*
X29698Y52302D01*
Y50988D01*
X30201Y49775D01*
X30745Y49230D01*
X30937Y48315D01*
X30696Y47651D01*
X30081Y47036D01*
X29578Y45823D01*
Y44509D01*
X30081Y43295D01*
X31010Y42367D01*
X31302Y42245D01*
Y40871D01*
X31130Y40799D01*
X30201Y39870D01*
X29698Y38657D01*
Y37343D01*
X30201Y36130D01*
X31130Y35201D01*
X31162Y35187D01*
Y33813D01*
X31130Y33799D01*
X30201Y32870D01*
X29698Y31657D01*
Y30343D01*
X29728Y30270D01*
X28880Y29000D01*
X14429D01*
X14422Y29036D01*
X13675Y30838D01*
X12791Y32162D01*
X11412Y33541D01*
X11412Y33541D01*
X10088Y34425D01*
X10088Y34425D01*
X8286Y35172D01*
X7699Y35289D01*
X7125Y35463D01*
X6150Y35559D01*
X5948Y35539D01*
X5750Y35578D01*
X4078D01*
X4078Y415922D01*
X215922D01*
X215922Y35578D01*
D02*
G37*
%LPC*%
G36*
X69370Y406589D02*
X68057D01*
X66843Y406086D01*
X65914Y405157D01*
X65411Y403943D01*
Y402630D01*
X65914Y401416D01*
X66843Y400487D01*
X68057Y399985D01*
X69370D01*
X70584Y400487D01*
X71513Y401416D01*
X72015Y402630D01*
Y403943D01*
X71513Y405157D01*
X70584Y406086D01*
X69370Y406589D01*
D02*
G37*
G36*
X32071Y406486D02*
X30757D01*
X29543Y405984D01*
X28614Y405055D01*
X28112Y403841D01*
Y402527D01*
X28614Y401314D01*
X29543Y400385D01*
X30757Y399882D01*
X32071D01*
X33284Y400385D01*
X34213Y401314D01*
X34716Y402527D01*
Y403841D01*
X34213Y405055D01*
X33284Y405984D01*
X32071Y406486D01*
D02*
G37*
G36*
X18087Y404809D02*
X16774D01*
X15560Y404306D01*
X14631Y403377D01*
X14128Y402164D01*
Y400850D01*
X14631Y399637D01*
X15560Y398708D01*
X16774Y398205D01*
X18087D01*
X19301Y398708D01*
X19368Y398775D01*
X20587Y399152D01*
X21516Y398224D01*
X22729Y397721D01*
X24043D01*
X25257Y398224D01*
X26186Y399152D01*
X26688Y400366D01*
Y401680D01*
X26186Y402893D01*
X25257Y403822D01*
X24043Y404325D01*
X22729D01*
X21516Y403822D01*
X21448Y403755D01*
X20230Y403377D01*
X19301Y404306D01*
X18087Y404809D01*
D02*
G37*
G36*
X40480Y365157D02*
X39167D01*
X37953Y364655D01*
X37024Y363726D01*
X36521Y362512D01*
Y361198D01*
X37024Y359985D01*
X37953Y359056D01*
X39167Y358553D01*
X40480D01*
X41694Y359056D01*
X42623Y359985D01*
X43126Y361198D01*
Y362512D01*
X42623Y363726D01*
X41694Y364655D01*
X40480Y365157D01*
D02*
G37*
G36*
X54631Y362951D02*
X53317D01*
X52104Y362449D01*
X51175Y361520D01*
X50672Y360306D01*
Y358992D01*
X51175Y357779D01*
X52104Y356850D01*
X53317Y356347D01*
X54631D01*
X55844Y356850D01*
X56773Y357779D01*
X57276Y358992D01*
Y360306D01*
X56773Y361520D01*
X55844Y362449D01*
X54631Y362951D01*
D02*
G37*
G36*
X26657Y352302D02*
X25343D01*
X24130Y351799D01*
X23201Y350870D01*
X22698Y349657D01*
Y348343D01*
X23201Y347130D01*
X24130Y346201D01*
X25343Y345698D01*
X26657D01*
X27870Y346201D01*
X28799Y347130D01*
X29302Y348343D01*
Y349657D01*
X28799Y350870D01*
X27870Y351799D01*
X26657Y352302D01*
D02*
G37*
G36*
X11657D02*
X10343D01*
X9130Y351799D01*
X8201Y350870D01*
X7698Y349657D01*
Y348343D01*
X8201Y347130D01*
X9130Y346201D01*
X10343Y345698D01*
X11657D01*
X12870Y346201D01*
X13799Y347130D01*
X14302Y348343D01*
Y349657D01*
X13799Y350870D01*
X12870Y351799D01*
X11657Y352302D01*
D02*
G37*
G36*
X19176Y347296D02*
X17862D01*
X16648Y346794D01*
X15720Y345865D01*
X15217Y344651D01*
Y343338D01*
X15720Y342124D01*
X16648Y341195D01*
X17862Y340692D01*
X19176D01*
X20389Y341195D01*
X21318Y342124D01*
X21821Y343338D01*
Y344651D01*
X21318Y345865D01*
X20389Y346794D01*
X19176Y347296D01*
D02*
G37*
G36*
X50572Y344654D02*
X49258D01*
X48045Y344151D01*
X47116Y343222D01*
X46613Y342008D01*
Y340695D01*
X47116Y339481D01*
X48045Y338552D01*
X49258Y338050D01*
X50572D01*
X51786Y338552D01*
X52715Y339481D01*
X53217Y340695D01*
Y342008D01*
X52715Y343222D01*
X51786Y344151D01*
X50572Y344654D01*
D02*
G37*
G36*
X11657Y342302D02*
X10343D01*
X9130Y341799D01*
X8201Y340870D01*
X7698Y339657D01*
Y338343D01*
X8201Y337130D01*
X9130Y336201D01*
X10343Y335698D01*
X11657D01*
X12870Y336201D01*
X13799Y337130D01*
X14302Y338343D01*
Y339657D01*
X13799Y340870D01*
X12870Y341799D01*
X11657Y342302D01*
D02*
G37*
G36*
X149680Y337477D02*
X148367D01*
X147153Y336975D01*
X146224Y336046D01*
X145722Y334832D01*
Y333518D01*
X146224Y332305D01*
X147153Y331376D01*
X148367Y330873D01*
X149680D01*
X150894Y331376D01*
X151823Y332305D01*
X152326Y333518D01*
Y334832D01*
X151823Y336046D01*
X150894Y336975D01*
X149680Y337477D01*
D02*
G37*
G36*
X127566Y337334D02*
X126252D01*
X125039Y336831D01*
X124110Y335902D01*
X123607Y334688D01*
Y333375D01*
X124110Y332161D01*
X125039Y331232D01*
X126252Y330730D01*
X127566D01*
X128779Y331232D01*
X129708Y332161D01*
X130211Y333375D01*
Y334688D01*
X129708Y335902D01*
X128779Y336831D01*
X127566Y337334D01*
D02*
G37*
G36*
X138480Y336616D02*
X137166D01*
X135952Y336113D01*
X135023Y335184D01*
X134521Y333970D01*
Y332657D01*
X135023Y331443D01*
X135952Y330514D01*
X137166Y330012D01*
X138480D01*
X139693Y330514D01*
X140622Y331443D01*
X141125Y332657D01*
Y333970D01*
X140622Y335184D01*
X139693Y336113D01*
X138480Y336616D01*
D02*
G37*
G36*
X210657Y316402D02*
X209343D01*
X208130Y315899D01*
X207201Y314970D01*
X206698Y313757D01*
Y312443D01*
X207201Y311230D01*
X208130Y310301D01*
X209343Y309798D01*
X210657D01*
X211870Y310301D01*
X212799Y311230D01*
X213302Y312443D01*
Y313757D01*
X212799Y314970D01*
X211870Y315899D01*
X210657Y316402D01*
D02*
G37*
G36*
Y305402D02*
X209343D01*
X208130Y304899D01*
X207201Y303971D01*
X206698Y302757D01*
Y301443D01*
X207201Y300230D01*
X208130Y299301D01*
X209343Y298798D01*
X210657D01*
X211870Y299301D01*
X212799Y300230D01*
X213302Y301443D01*
Y302757D01*
X212799Y303971D01*
X211870Y304899D01*
X210657Y305402D01*
D02*
G37*
G36*
Y261402D02*
X209343D01*
X208130Y260899D01*
X207201Y259970D01*
X206698Y258757D01*
Y257443D01*
X207201Y256230D01*
X208130Y255301D01*
X209343Y254798D01*
X210657D01*
X211870Y255301D01*
X212799Y256230D01*
X213302Y257443D01*
Y258757D01*
X212799Y259970D01*
X211870Y260899D01*
X210657Y261402D01*
D02*
G37*
G36*
Y239402D02*
X209343D01*
X208130Y238899D01*
X207201Y237971D01*
X206698Y236757D01*
Y235443D01*
X207201Y234230D01*
X208130Y233301D01*
X209343Y232798D01*
X210657D01*
X211870Y233301D01*
X212799Y234230D01*
X213302Y235443D01*
Y236757D01*
X212799Y237971D01*
X211870Y238899D01*
X210657Y239402D01*
D02*
G37*
G36*
Y217402D02*
X209343D01*
X208130Y216899D01*
X207201Y215970D01*
X206698Y214757D01*
Y213443D01*
X207201Y212230D01*
X208130Y211301D01*
X209343Y210798D01*
X210657D01*
X211870Y211301D01*
X212799Y212230D01*
X213302Y213443D01*
Y214757D01*
X212799Y215970D01*
X211870Y216899D01*
X210657Y217402D01*
D02*
G37*
G36*
Y206402D02*
X209343D01*
X208130Y205899D01*
X207201Y204970D01*
X206698Y203757D01*
Y202443D01*
X207201Y201230D01*
X208130Y200301D01*
X209343Y199798D01*
X210657D01*
X211870Y200301D01*
X212799Y201230D01*
X213302Y202443D01*
Y203757D01*
X212799Y204970D01*
X211870Y205899D01*
X210657Y206402D01*
D02*
G37*
G36*
Y195402D02*
X209343D01*
X208130Y194899D01*
X207201Y193971D01*
X206698Y192757D01*
Y191443D01*
X207201Y190230D01*
X208130Y189301D01*
X209343Y188798D01*
X210657D01*
X211870Y189301D01*
X212799Y190230D01*
X213302Y191443D01*
Y192757D01*
X212799Y193971D01*
X211870Y194899D01*
X210657Y195402D01*
D02*
G37*
G36*
Y184402D02*
X209343D01*
X208130Y183899D01*
X207201Y182971D01*
X206698Y181757D01*
Y180443D01*
X207201Y179230D01*
X208130Y178301D01*
X209343Y177798D01*
X210657D01*
X211870Y178301D01*
X212799Y179230D01*
X213302Y180443D01*
Y181757D01*
X212799Y182971D01*
X211870Y183899D01*
X210657Y184402D01*
D02*
G37*
G36*
X106834Y150302D02*
X105521D01*
X104307Y149799D01*
X103378Y148870D01*
X102876Y147657D01*
Y146343D01*
X103378Y145130D01*
X104307Y144201D01*
X105521Y143698D01*
X106834D01*
X108048Y144201D01*
X108977Y145130D01*
X109480Y146343D01*
Y147657D01*
X108977Y148870D01*
X108048Y149799D01*
X106834Y150302D01*
D02*
G37*
G36*
X92487Y150186D02*
X91174D01*
X89960Y149683D01*
X89031Y148754D01*
X88529Y147541D01*
Y146227D01*
X89031Y145013D01*
X89960Y144085D01*
X91174Y143582D01*
X92487D01*
X93701Y144085D01*
X94630Y145013D01*
X95133Y146227D01*
Y147541D01*
X94630Y148754D01*
X93701Y149683D01*
X92487Y150186D01*
D02*
G37*
G36*
X52759Y142744D02*
X51445D01*
X50232Y142241D01*
X49303Y141313D01*
X48800Y140099D01*
Y138785D01*
X49303Y137572D01*
X50232Y136643D01*
X51445Y136140D01*
X52759D01*
X53972Y136643D01*
X54901Y137572D01*
X55404Y138785D01*
Y140099D01*
X54901Y141313D01*
X53972Y142241D01*
X52759Y142744D01*
D02*
G37*
G36*
X115657Y142302D02*
X114343D01*
X113130Y141799D01*
X112201Y140870D01*
X111698Y139657D01*
Y138343D01*
X112201Y137130D01*
X113130Y136201D01*
X114343Y135698D01*
X115657D01*
X116870Y136201D01*
X117799Y137130D01*
X118302Y138343D01*
Y139657D01*
X117799Y140870D01*
X116870Y141799D01*
X115657Y142302D01*
D02*
G37*
G36*
X128871Y141302D02*
X127558D01*
X126344Y140799D01*
X125415Y139870D01*
X124912Y138657D01*
Y137343D01*
X125415Y136130D01*
X126344Y135201D01*
X127558Y134698D01*
X128871D01*
X130085Y135201D01*
X131014Y136130D01*
X131516Y137343D01*
Y138657D01*
X131014Y139870D01*
X130085Y140799D01*
X128871Y141302D01*
D02*
G37*
G36*
X168657Y134302D02*
X167343D01*
X166130Y133799D01*
X165201Y132870D01*
X164698Y131657D01*
Y130343D01*
X165201Y129130D01*
X166130Y128201D01*
X167343Y127698D01*
X168657D01*
X169870Y128201D01*
X170799Y129130D01*
X171302Y130343D01*
Y131657D01*
X170799Y132870D01*
X169870Y133799D01*
X168657Y134302D01*
D02*
G37*
G36*
X77268Y130474D02*
X75954D01*
X74740Y129972D01*
X73812Y129043D01*
X73309Y127829D01*
Y126515D01*
X73812Y125302D01*
X74740Y124373D01*
X75954Y123870D01*
X77268D01*
X78481Y124373D01*
X79410Y125302D01*
X79913Y126515D01*
Y127829D01*
X79410Y129043D01*
X78481Y129972D01*
X77268Y130474D01*
D02*
G37*
G36*
X201657Y123302D02*
X200343D01*
X199130Y122799D01*
X198201Y121870D01*
X197698Y120657D01*
Y119343D01*
X198201Y118130D01*
X199130Y117201D01*
X200343Y116698D01*
X201657D01*
X202870Y117201D01*
X203799Y118130D01*
X204302Y119343D01*
Y120657D01*
X203799Y121870D01*
X202870Y122799D01*
X201657Y123302D01*
D02*
G37*
G36*
X167657D02*
X166343D01*
X165130Y122799D01*
X164201Y121870D01*
X163698Y120657D01*
Y119343D01*
X164201Y118130D01*
X165130Y117201D01*
X166343Y116698D01*
X167657D01*
X168870Y117201D01*
X169799Y118130D01*
X170302Y119343D01*
Y120657D01*
X169799Y121870D01*
X168870Y122799D01*
X167657Y123302D01*
D02*
G37*
G36*
X42449Y120544D02*
X41135D01*
X39922Y120041D01*
X38993Y119112D01*
X38490Y117898D01*
Y116585D01*
X38993Y115371D01*
X39922Y114442D01*
X41135Y113940D01*
X42449D01*
X43663Y114442D01*
X44591Y115371D01*
X45094Y116585D01*
Y117898D01*
X44591Y119112D01*
X43663Y120041D01*
X42449Y120544D01*
D02*
G37*
G36*
X95450Y115521D02*
X94137D01*
X92923Y115018D01*
X91994Y114089D01*
X91491Y112875D01*
Y111562D01*
X91994Y110348D01*
X92923Y109419D01*
X94137Y108917D01*
X95450D01*
X96664Y109419D01*
X97593Y110348D01*
X98095Y111562D01*
Y112875D01*
X97593Y114089D01*
X96664Y115018D01*
X95450Y115521D01*
D02*
G37*
G36*
X166657Y115302D02*
X165343D01*
X164130Y114799D01*
X163201Y113870D01*
X162698Y112657D01*
Y111343D01*
X163201Y110130D01*
X164130Y109201D01*
X165343Y108698D01*
X166657D01*
X167870Y109201D01*
X168799Y110130D01*
X169302Y111343D01*
Y112657D01*
X168799Y113870D01*
X167870Y114799D01*
X166657Y115302D01*
D02*
G37*
G36*
X66657D02*
X65343D01*
X64130Y114799D01*
X63201Y113870D01*
X62698Y112657D01*
Y111343D01*
X63201Y110130D01*
X64130Y109201D01*
X65343Y108698D01*
X66657D01*
X67870Y109201D01*
X68799Y110130D01*
X69302Y111343D01*
Y112657D01*
X68799Y113870D01*
X67870Y114799D01*
X66657Y115302D01*
D02*
G37*
G36*
X204657Y114302D02*
X203343D01*
X202130Y113799D01*
X201201Y112870D01*
X200698Y111657D01*
Y110343D01*
X201201Y109130D01*
X202130Y108201D01*
X203343Y107698D01*
X204657D01*
X205870Y108201D01*
X206799Y109130D01*
X207302Y110343D01*
Y111657D01*
X206799Y112870D01*
X205870Y113799D01*
X204657Y114302D01*
D02*
G37*
G36*
X93714Y104897D02*
X92400D01*
X91187Y104395D01*
X90258Y103466D01*
X89755Y102252D01*
Y100939D01*
X90258Y99725D01*
X91187Y98796D01*
X92400Y98293D01*
X93714D01*
X94927Y98796D01*
X95856Y99725D01*
X96359Y100939D01*
Y102252D01*
X95856Y103466D01*
X94927Y104395D01*
X93714Y104897D01*
D02*
G37*
G36*
X66645Y103671D02*
X65332D01*
X64118Y103168D01*
X63189Y102240D01*
X62686Y101026D01*
Y99712D01*
X63189Y98499D01*
X64118Y97570D01*
X65332Y97067D01*
X66645D01*
X67859Y97570D01*
X68788Y98499D01*
X69290Y99712D01*
Y101026D01*
X68788Y102240D01*
X67859Y103168D01*
X66645Y103671D01*
D02*
G37*
G36*
X90819Y88876D02*
X89506D01*
X88292Y88373D01*
X87363Y87444D01*
X86861Y86231D01*
Y84917D01*
X87363Y83704D01*
X88292Y82775D01*
X89506Y82272D01*
X90819D01*
X92033Y82775D01*
X92962Y83704D01*
X93464Y84917D01*
Y86231D01*
X92962Y87444D01*
X92033Y88373D01*
X90819Y88876D01*
D02*
G37*
G36*
X38415Y76302D02*
X37101D01*
X35887Y75799D01*
X34959Y74870D01*
X34456Y73657D01*
Y72343D01*
X34959Y71130D01*
X35887Y70201D01*
X37101Y69698D01*
X38415D01*
X39628Y70201D01*
X40557Y71130D01*
X41060Y72343D01*
Y73657D01*
X40557Y74870D01*
X39628Y75799D01*
X38415Y76302D01*
D02*
G37*
G36*
X81169Y70918D02*
X79855D01*
X78642Y70415D01*
X77713Y69486D01*
X77210Y68273D01*
Y66959D01*
X77713Y65745D01*
X78642Y64817D01*
X79855Y64314D01*
X81169D01*
X82382Y64817D01*
X83311Y65745D01*
X83814Y66959D01*
Y68273D01*
X83311Y69486D01*
X82382Y70415D01*
X81169Y70918D01*
D02*
G37*
G36*
X37657Y67302D02*
X36343D01*
X35130Y66799D01*
X34201Y65870D01*
X33698Y64657D01*
Y63343D01*
X34201Y62130D01*
X35130Y61201D01*
X36343Y60698D01*
X37657D01*
X38870Y61201D01*
X39799Y62130D01*
X40302Y63343D01*
Y64657D01*
X39799Y65870D01*
X38870Y66799D01*
X37657Y67302D01*
D02*
G37*
G36*
X107605Y65774D02*
X106292D01*
X105078Y65272D01*
X104149Y64343D01*
X103646Y63129D01*
Y61815D01*
X104149Y60602D01*
X105078Y59673D01*
X106292Y59170D01*
X107605D01*
X108819Y59673D01*
X109748Y60602D01*
X110250Y61815D01*
Y63129D01*
X109748Y64343D01*
X108819Y65272D01*
X107605Y65774D01*
D02*
G37*
G36*
X206657Y55302D02*
X205343D01*
X204130Y54799D01*
X203201Y53870D01*
X202698Y52657D01*
Y51343D01*
X203201Y50130D01*
X204130Y49201D01*
X205343Y48698D01*
X206657D01*
X207870Y49201D01*
X208799Y50130D01*
X209302Y51343D01*
Y52657D01*
X208799Y53870D01*
X207870Y54799D01*
X206657Y55302D01*
D02*
G37*
G36*
X197657D02*
X196343D01*
X195130Y54799D01*
X194201Y53870D01*
X193698Y52657D01*
Y51343D01*
X194201Y50130D01*
X195130Y49201D01*
X196343Y48698D01*
X197657D01*
X198870Y49201D01*
X199799Y50130D01*
X200302Y51343D01*
Y52657D01*
X199799Y53870D01*
X198870Y54799D01*
X197657Y55302D01*
D02*
G37*
%LPD*%
D58*
X211156Y38620D02*
D03*
X126000Y100000D02*
D03*
X104000Y107000D02*
D03*
X209830Y407680D02*
D03*
Y397520D02*
D03*
Y387360D02*
D03*
Y377200D02*
D03*
Y367040D02*
D03*
Y356880D02*
D03*
Y346720D02*
D03*
Y336560D02*
D03*
Y326400D02*
D03*
X199670Y407680D02*
D03*
Y397520D02*
D03*
Y387360D02*
D03*
Y377200D02*
D03*
Y367040D02*
D03*
Y356880D02*
D03*
Y346720D02*
D03*
Y336560D02*
D03*
Y326400D02*
D03*
X189510Y387360D02*
D03*
Y367040D02*
D03*
Y356880D02*
D03*
Y346720D02*
D03*
Y336560D02*
D03*
Y326400D02*
D03*
X179350Y367040D02*
D03*
Y356880D02*
D03*
Y346720D02*
D03*
Y336560D02*
D03*
X169190Y407680D02*
D03*
X159030Y387360D02*
D03*
Y377200D02*
D03*
Y356880D02*
D03*
Y346720D02*
D03*
Y336560D02*
D03*
X148870Y387360D02*
D03*
Y346720D02*
D03*
X138710Y397520D02*
D03*
Y387360D02*
D03*
X128550D02*
D03*
X118390D02*
D03*
X98070D02*
D03*
X87910Y306080D02*
D03*
X77750Y407680D02*
D03*
Y387360D02*
D03*
Y356880D02*
D03*
X67590Y397520D02*
D03*
Y306080D02*
D03*
Y295920D02*
D03*
Y285760D02*
D03*
Y275600D02*
D03*
X190545Y43935D02*
D03*
X115000Y146000D02*
D03*
X106178Y147000D02*
D03*
X115000Y139000D02*
D03*
X168000Y131000D02*
D03*
X204000Y111000D02*
D03*
X166000Y112000D02*
D03*
X201000Y120000D02*
D03*
X167000D02*
D03*
X154373Y105997D02*
D03*
X210000Y181100D02*
D03*
Y192100D02*
D03*
X76611Y127172D02*
D03*
X52102Y139442D02*
D03*
X53051Y126729D02*
D03*
X41792Y117242D02*
D03*
X39452Y130651D02*
D03*
X12000Y65000D02*
D03*
Y74000D02*
D03*
X37758Y73000D02*
D03*
X37000Y64000D02*
D03*
X206000Y52000D02*
D03*
X197000D02*
D03*
X207000Y77000D02*
D03*
X198000D02*
D03*
X204000Y40054D02*
D03*
X191000Y37000D02*
D03*
X90162Y85574D02*
D03*
X80512Y67616D02*
D03*
X106948Y62472D02*
D03*
X93057Y101595D02*
D03*
X94793Y112219D02*
D03*
X65988Y100369D02*
D03*
X66000Y112000D02*
D03*
X145027Y145180D02*
D03*
X128214Y138000D02*
D03*
X181826Y161442D02*
D03*
X148849Y161221D02*
D03*
X138262Y162104D02*
D03*
X83228D02*
D03*
X83000Y146000D02*
D03*
X91831Y146884D02*
D03*
X37000Y194600D02*
D03*
X58000D02*
D03*
X79000D02*
D03*
X100000Y194000D02*
D03*
X121000Y194600D02*
D03*
X142000D02*
D03*
X163000D02*
D03*
X184000Y194600D02*
D03*
X37000Y215600D02*
D03*
X58000D02*
D03*
X79000D02*
D03*
X100000Y215000D02*
D03*
X121000Y215600D02*
D03*
X142000D02*
D03*
X163000D02*
D03*
X184000Y215600D02*
D03*
X37000Y236600D02*
D03*
X58000D02*
D03*
X79000D02*
D03*
X100000Y236000D02*
D03*
X121000Y236600D02*
D03*
X142000D02*
D03*
X163000D02*
D03*
X184000Y236600D02*
D03*
X37000Y257000D02*
D03*
X58000D02*
D03*
X79000D02*
D03*
X100000Y256400D02*
D03*
X121000Y257000D02*
D03*
X142000D02*
D03*
X163000D02*
D03*
X184000Y257000D02*
D03*
X37000Y278600D02*
D03*
X58000D02*
D03*
X79000D02*
D03*
X100000Y278000D02*
D03*
X121000Y278600D02*
D03*
X142000D02*
D03*
X163000D02*
D03*
X184000Y278600D02*
D03*
Y299600D02*
D03*
X163000Y299600D02*
D03*
X142000D02*
D03*
X121000D02*
D03*
X100000Y299000D02*
D03*
X79000Y299600D02*
D03*
X58000D02*
D03*
X37000D02*
D03*
X210000Y203100D02*
D03*
Y214100D02*
D03*
Y236100D02*
D03*
Y258100D02*
D03*
Y302100D02*
D03*
Y313100D02*
D03*
X149024Y334175D02*
D03*
X137823Y333314D02*
D03*
X126909Y334032D02*
D03*
X17430Y401507D02*
D03*
X68713Y403287D02*
D03*
X14291Y409878D02*
D03*
X11151Y401828D02*
D03*
X53974Y359649D02*
D03*
X23386Y401023D02*
D03*
X51000Y371000D02*
D03*
X50396Y377474D02*
D03*
X31414Y403184D02*
D03*
X11000Y339000D02*
D03*
X18519Y343994D02*
D03*
X26000Y349000D02*
D03*
X11000D02*
D03*
X49915Y341352D02*
D03*
X39824Y361855D02*
D03*
X63000Y38000D02*
D03*
X176000Y44000D02*
D03*
X111000Y35000D02*
D03*
X152000Y36000D02*
D03*
X137000D02*
D03*
X123000Y35000D02*
D03*
X93000Y34000D02*
D03*
X33000Y31000D02*
D03*
Y38000D02*
D03*
X32880Y45166D02*
D03*
X33000Y51645D02*
D03*
X15000Y50312D02*
D03*
X12791Y42000D02*
D03*
X6395Y41971D02*
D03*
X6826Y50312D02*
D03*
D59*
X110000Y420000D02*
D03*
M02*
